# SCM (Grand Teton) — schematic netlist excerpt (pin names and nets, part order shuffled) for the footprints in the layout excerpt that follows; sources: Cadence DE-HDL packaged netlist, KiCad conversion of 12092022_DA0F0TMDCD0_F0T_Management_Board_D_brd_V3_OCP.brd

R224  Q_RES  33.2 1% CHIP  pkg 0402LF  page 32 : A = JTAG_1_BMC_TDO_R ; B = JTAG_MB_TDO
ME2  ME_DUMMY_SYMBOL  WEEE EMPTY  pkg WEEE  page 59
R696  Q_RES  0 5% CHIP  pkg 0402LF  page 47 : A = LED_POSTCODE_3 ; B = LED_POSTCODE_3_R1

(kicad_pcb
	(version 20260206)
	(generator "pcbnew")
	(generator_version "10.0")
	(general
		(thickness 1.6)
		(legacy_teardrops no)
	)
	(paper "A4")
	(title_block
		(title "12092022_DA0F0TMDCD0_F0T_Management_Board_D_brd_V3_OCP.brd")
		(comment 1 "Grand Teton / footprints 1332-1334 of 1440")
	)
	(layers
		(0 "F.Cu" signal "TOP")
		(4 "In1.Cu" signal "GND")
		(6 "In2.Cu" signal "IN1")
		(8 "In3.Cu" signal "GND1")
		(10 "In4.Cu" signal "IN2")
		(12 "In5.Cu" signal "VCC")
		(14 "In6.Cu" signal "VCC1")
		(16 "In7.Cu" signal "IN3")
		(18 "In8.Cu" signal "GND2")
		(20 "In9.Cu" signal "IN4")
		(22 "In10.Cu" signal "GND3")
		(2 "B.Cu" signal "BOTTOM")
		(9 "F.Adhes" user "F.Adhesive")
		(11 "B.Adhes" user "B.Adhesive")
		(13 "F.Paste" user "Package Geometry/Pastemask Top")
		(15 "B.Paste" user "Package Geometry/Pastemask Bottom")
		(5 "F.SilkS" user "Ref Des/Silkscreen Top")
		(7 "B.SilkS" user "Ref Des/Silkscreen Bottom")
		(1 "F.Mask" user "Board Geometry/Soldermask Top")
		(3 "B.Mask" user "Board Geometry/Soldermask Bottom")
		(17 "Dwgs.User" user "User.Drawings")
		(19 "Cmts.User" user "User.Comments")
		(21 "Eco1.User" user "User.Eco1")
		(23 "Eco2.User" user "User.Eco2")
		(25 "Edge.Cuts" user "Board Geometry/Outline")
		(27 "Margin" user)
		(31 "F.CrtYd" user "Package Geometry/Place Bound Top")
		(29 "B.CrtYd" user "Package Geometry/Place Bound Bottom")
		(35 "F.Fab" user "Ref Des/Assembly Top")
		(33 "B.Fab" user "Ref Des/Assembly Bottom")
	)
	(footprint ""
		(layer "B.Cu")
		(at 36.068 -106.3625 -90)
		(property "Reference" "R224"
			(at 0 0 90)
			(layer "B.SilkS")
			(hide yes)
			(effects
				(font
					(size 1.27 1.27)
				)
				(justify mirror)
			)
		)
		(property "Value" ""
			(at 0 0 90)
			(layer "B.Fab")
			(effects
				(font
					(size 1.27 1.27)
				)
				(justify mirror)
			)
		)
		(duplicate_pad_numbers_are_jumpers no)
		(fp_line
			(start -0.7874 0.4064)
			(end 0.7874 0.4064)
			(stroke
				(width 0.1524)
				(type default)
			)
			(layer "B.SilkS")
		)
		(fp_line
			(start 0.7874 0.4064)
			(end 0.7874 -0.4064)
			(stroke
				(width 0.1524)
				(type default)
			)
			(layer "B.SilkS")
		)
		(fp_line
			(start -0.7874 -0.4064)
			(end -0.7874 0.4064)
			(stroke
				(width 0.1524)
				(type default)
			)
			(layer "B.SilkS")
		)
		(fp_line
			(start 0.7874 -0.4064)
			(end -0.7874 -0.4064)
			(stroke
				(width 0.1524)
				(type default)
			)
			(layer "B.SilkS")
		)
		(fp_line
			(start -0.67945 0.3048)
			(end -0.120396 0.3048)
			(stroke
				(width 0.1)
				(type default)
			)
			(layer "B.Fab")
		)
		(fp_line
			(start -0.120396 0.3048)
			(end -0.120396 0.2794)
			(stroke
				(width 0.1)
				(type default)
			)
			(layer "B.Fab")
		)
		(fp_line
			(start 0.12065 0.3048)
			(end 0.67945 0.3048)
			(stroke
				(width 0.1)
				(type default)
			)
			(layer "B.Fab")
		)
		(fp_line
			(start 0.67945 0.3048)
			(end 0.67945 -0.305054)
			(stroke
				(width 0.1)
				(type default)
			)
			(layer "B.Fab")
		)
		(fp_line
			(start -0.120396 0.2794)
			(end 0.12065 0.2794)
			(stroke
				(width 0.1)
				(type default)
			)
			(layer "B.Fab")
		)
		(fp_line
			(start 0.12065 0.2794)
			(end 0.12065 0.3048)
			(stroke
				(width 0.1)
				(type default)
			)
			(layer "B.Fab")
		)
		(fp_line
			(start -0.12065 -0.2794)
			(end -0.12065 -0.3048)
			(stroke
				(width 0.1)
				(type default)
			)
			(layer "B.Fab")
		)
		(fp_line
			(start 0.12065 -0.2794)
			(end -0.12065 -0.2794)
			(stroke
				(width 0.1)
				(type default)
			)
			(layer "B.Fab")
		)
		(fp_line
			(start -0.67945 -0.3048)
			(end -0.67945 0.3048)
			(stroke
				(width 0.1)
				(type default)
			)
			(layer "B.Fab")
		)
		(fp_line
			(start -0.12065 -0.3048)
			(end -0.67945 -0.3048)
			(stroke
				(width 0.1)
				(type default)
			)
			(layer "B.Fab")
		)
		(fp_line
			(start 0.12065 -0.305054)
			(end 0.12065 -0.2794)
			(stroke
				(width 0.1)
				(type default)
			)
			(layer "B.Fab")
		)
		(fp_line
			(start 0.67945 -0.305054)
			(end 0.12065 -0.305054)
			(stroke
				(width 0.1)
				(type default)
			)
			(layer "B.Fab")
		)
		(pad "1" smd circle
			(at 0.40005 0 90)
			(size 0 0)
			(layers "B.Cu" "B.Mask" "B.Paste")
			(net "JTAG_1_BMC_TDO_R")
		)
		(pad "2" smd circle
			(at -0.40005 0 90)
			(size 0 0)
			(layers "B.Cu" "B.Mask" "B.Paste")
			(net "JTAG_MB_TDO")
		)
	)
	(footprint ""
		(layer "B.Cu")
		(at 75.438 -24.7904 180)
		(property "Reference" "R696"
			(at 0 0 0)
			(layer "B.SilkS")
			(hide yes)
			(effects
				(font
					(size 1.27 1.27)
				)
				(justify mirror)
			)
		)
		(property "Value" ""
			(at 0 0 0)
			(layer "B.Fab")
			(effects
				(font
					(size 1.27 1.27)
				)
				(justify mirror)
			)
		)
		(duplicate_pad_numbers_are_jumpers no)
		(fp_line
			(start 0.7874 0.4064)
			(end 0.7874 -0.4064)
			(stroke
				(width 0.1524)
				(type default)
			)
			(layer "B.SilkS")
		)
		(fp_line
			(start 0.7874 -0.4064)
			(end -0.7874 -0.4064)
			(stroke
				(width 0.1524)
				(type default)
			)
			(layer "B.SilkS")
		)
		(fp_line
			(start -0.7874 0.4064)
			(end 0.7874 0.4064)
			(stroke
				(width 0.1524)
				(type default)
			)
			(layer "B.SilkS")
		)
		(fp_line
			(start -0.7874 -0.4064)
			(end -0.7874 0.4064)
			(stroke
				(width 0.1524)
				(type default)
			)
			(layer "B.SilkS")
		)
		(fp_line
			(start 0.67945 0.3048)
			(end 0.67945 -0.305054)
			(stroke
				(width 0.1)
				(type default)
			)
			(layer "B.Fab")
		)
		(fp_line
			(start 0.67945 -0.305054)
			(end 0.12065 -0.305054)
			(stroke
				(width 0.1)
				(type default)
			)
			(layer "B.Fab")
		)
		(fp_line
			(start 0.12065 0.3048)
			(end 0.67945 0.3048)
			(stroke
				(width 0.1)
				(type default)
			)
			(layer "B.Fab")
		)
		(fp_line
			(start 0.12065 0.2794)
			(end 0.12065 0.3048)
			(stroke
				(width 0.1)
				(type default)
			)
			(layer "B.Fab")
		)
		(fp_line
			(start 0.12065 -0.2794)
			(end -0.12065 -0.2794)
			(stroke
				(width 0.1)
				(type default)
			)
			(layer "B.Fab")
		)
		(fp_line
			(start 0.12065 -0.305054)
			(end 0.12065 -0.2794)
			(stroke
				(width 0.1)
				(type default)
			)
			(layer "B.Fab")
		)
		(fp_line
			(start -0.120396 0.3048)
			(end -0.120396 0.2794)
			(stroke
				(width 0.1)
				(type default)
			)
			(layer "B.Fab")
		)
		(fp_line
			(start -0.120396 0.2794)
			(end 0.12065 0.2794)
			(stroke
				(width 0.1)
				(type default)
			)
			(layer "B.Fab")
		)
		(fp_line
			(start -0.12065 -0.2794)
			(end -0.12065 -0.3048)
			(stroke
				(width 0.1)
				(type default)
			)
			(layer "B.Fab")
		)
		(fp_line
			(start -0.12065 -0.3048)
			(end -0.67945 -0.3048)
			(stroke
				(width 0.1)
				(type default)
			)
			(layer "B.Fab")
		)
		(fp_line
			(start -0.67945 0.3048)
			(end -0.120396 0.3048)
			(stroke
				(width 0.1)
				(type default)
			)
			(layer "B.Fab")
		)
		(fp_line
			(start -0.67945 -0.3048)
			(end -0.67945 0.3048)
			(stroke
				(width 0.1)
				(type default)
			)
			(layer "B.Fab")
		)
		(pad "1" smd circle
			(at 0.40005 0)
			(size 0 0)
			(layers "B.Cu" "B.Mask" "B.Paste")
			(net "LED_POSTCODE_3")
		)
		(pad "2" smd circle
			(at -0.40005 0)
			(size 0 0)
			(layers "B.Cu" "B.Mask" "B.Paste")
			(net "LED_POSTCODE_3_R1")
		)
	)
	(footprint ""
		(layer "B.Cu")
		(at 11.557 -43.688)
		(property "Reference" "ME2"
			(at 0 0 0)
			(layer "B.SilkS")
			(hide yes)
			(effects
				(font
					(size 1.27 1.27)
				)
				(justify mirror)
			)
		)
		(property "Value" ""
			(at 0 0 0)
			(layer "B.Fab")
			(effects
				(font
					(size 1.27 1.27)
				)
				(justify mirror)
			)
		)
		(duplicate_pad_numbers_are_jumpers no)
		(fp_poly
			(pts
				(xy -1.32715 -3.4417) (xy -2.01295 -3.4417) (xy -2.01295 -3.2512) (xy -1.32715 -3.2512)
			)
			(stroke
				(width 0)
				(type default)
			)
			(fill yes)
			(layer "B.SilkS")
		)
		(fp_poly
			(pts
				(xy 0 -0.5842) (xy -3.3401 -0.5842) (xy -3.3401 0) (xy 0 0)
			)
			(stroke
				(width 0)
				(type default)
			)
			(fill yes)
			(layer "B.SilkS")
		)
		(fp_poly
			(pts
				(xy 0.070612 -0.681228) (xy 0.197612 -0.820928) (xy -0.852678 -1.91262) (xy -0.728472 -3.29184)
				(xy 0.248412 -4.300728) (xy 0.184912 -4.478528) (xy 0.007112 -4.503928) (xy -0.684022 -3.785616)
				(xy -0.65659 -4.0894) (xy -0.97155 -4.3434) (xy -1.22555 -4.3561) (xy -1.46685 -4.4704) (xy -2.01295 -4.4704)
				(xy -2.15265 -4.4069) (xy -2.44475 -4.191) (xy -2.49555 -4.191) (xy -2.59715 -4.2926) (xy -2.80035 -4.2672)
				(xy -2.88925 -4.1656) (xy -2.88925 -4.029456) (xy -3.345688 -4.503928) (xy -3.523488 -4.478528)
				(xy -3.586988 -4.300728) (xy -2.88925 -3.58013) (xy -2.88925 -3.3147) (xy -2.82575 -3.2385) (xy -2.67335 -3.2385)
				(xy -2.521966 -1.875282) (xy -2.545842 -1.85039)
				(arc
					(start -2.55905 -1.8415)
					(mid -2.648099 -1.766068)
					(end -2.717292 -1.672082)
				)
				(xy -3.536188 -0.820928) (xy -3.409188 -0.681228) (xy -3.244088 -0.693928)
				(arc
					(start -2.737612 -1.216914)
					(mid -2.31728 -0.925553)
					(end -1.86055 -1.1557)
				)
				(xy -0.92075 -1.1557) (xy -0.888492 -1.51384) (xy -0.094488 -0.693928)
			)
			(stroke
				(width 0)
				(type default)
			)
			(fill yes)
			(layer "B.SilkS")
		)
	)
)
